(kicad_pcb
	(version 20260206)
	(generator "pcbnew")
	(generator_version "10.0")
	(general
		(thickness 1.6)
		(legacy_teardrops no)
	)
	(paper "A4")
	(title_block
		(title "03242023_DA0F0TMBIJ0_F0T_Motherboard_J_brd_V01_OCP.brd")
		(comment 1 "Grand Teton / footprint 2194 of 6105 (J15), pads 1-112 of 291")
	)
	(layers
		(0 "F.Cu" signal "TOP")
		(4 "In1.Cu" signal "GND")
		(6 "In2.Cu" signal "IN1")
		(8 "In3.Cu" signal "GND1")
		(10 "In4.Cu" signal "IN2")
		(12 "In5.Cu" signal "GND2")
		(14 "In6.Cu" signal "IN3")
		(16 "In7.Cu" signal "GND3")
		(18 "In8.Cu" signal "VCC")
		(20 "In9.Cu" signal "VCC1")
		(22 "In10.Cu" signal "GND4")
		(24 "In11.Cu" signal "IN4")
		(26 "In12.Cu" signal "GND5")
		(28 "In13.Cu" signal "IN5")
		(30 "In14.Cu" signal "GND6")
		(32 "In15.Cu" signal "IN6")
		(34 "In16.Cu" signal "GND7")
		(2 "B.Cu" signal "BOTTOM")
		(9 "F.Adhes" user "F.Adhesive")
		(11 "B.Adhes" user "B.Adhesive")
		(13 "F.Paste" user "Package Geometry/Pastemask Top")
		(15 "B.Paste" user "Package Geometry/Pastemask Bottom")
		(5 "F.SilkS" user "Ref Des/Silkscreen Top")
		(7 "B.SilkS" user "Ref Des/Silkscreen Bottom")
		(1 "F.Mask" user "Board Geometry/Soldermask Top")
		(3 "B.Mask" user "Board Geometry/Soldermask Bottom")
		(17 "Dwgs.User" user "User.Drawings")
		(19 "Cmts.User" user "User.Comments")
		(21 "Eco1.User" user "User.Eco1")
		(23 "Eco2.User" user "User.Eco2")
		(25 "Edge.Cuts" user "Board Geometry/Outline")
		(27 "Margin" user)
		(31 "F.CrtYd" user "Package Geometry/Place Bound Top")
		(29 "B.CrtYd" user "Package Geometry/Place Bound Bottom")
		(35 "F.Fab" user "Ref Des/Assembly Top")
		(33 "B.Fab" user "Ref Des/Assembly Bottom")
	)
	(footprint ""
		(layer "F.Cu")
		(at 461.609948 -258.091686)
		(property "Reference" "J15"
			(at 3.019552 -81.652872 0)
			(unlocked yes)
			(layer "F.SilkS")
			(effects
				(font
					(size 0.7874 0.5842)
					(thickness 0.1524)
				)
				(justify left)
			)
		)
		(property "Value" ""
			(at 0 0 0)
			(layer "F.Fab")
			(effects
				(font
					(size 1.27 1.27)
				)
			)
		)
		(duplicate_pad_numbers_are_jumpers no)
		(pad "1" smd rect
			(at -2.050034 -63.324994 270)
			(size 0.519938 1.4986)
			(layers "F.Cu" "F.Mask" "F.Paste")
			(net "P12V_S3_AUX_CPU0_NVDIMM")
		)
		(pad "2" smd rect
			(at -2.050034 -62.47511 270)
			(size 0.519938 1.4986)
			(layers "F.Cu" "F.Mask" "F.Paste")
			(net "TP_CHH_CPU0_DIMM1_FRU_0")
		)
		(pad "3" smd rect
			(at -2.050034 -61.624972 270)
			(size 0.519938 1.4986)
			(layers "F.Cu" "F.Mask" "F.Paste")
			(net "P3V3_AUX")
		)
		(pad "4" smd rect
			(at -2.050034 -60.775088 270)
			(size 0.519938 1.4986)
			(layers "F.Cu" "F.Mask" "F.Paste")
			(net "I3C_SPD_DDREFGH_CPU0_LVC1_SCL_6")
		)
		(pad "5" smd rect
			(at -2.050034 -59.92495 270)
			(size 0.519938 1.4986)
			(layers "F.Cu" "F.Mask" "F.Paste")
			(net "I3C_SPD_DDREFGH_CPU0_LVC1_SDA")
		)
		(pad "6" smd rect
			(at -2.050034 -59.075066 270)
			(size 0.519938 1.4986)
			(layers "F.Cu" "F.Mask" "F.Paste")
			(net "GND")
		)
		(pad "7" smd rect
			(at -2.050034 -58.224928 270)
			(size 0.519938 1.4986)
			(layers "F.Cu" "F.Mask" "F.Paste")
			(net "M_H_CPU0_SA_DQ<0>")
		)
		(pad "8" smd rect
			(at -2.050034 -57.375044 270)
			(size 0.519938 1.4986)
			(layers "F.Cu" "F.Mask" "F.Paste")
			(net "GND")
		)
		(pad "9" smd rect
			(at -2.050034 -56.524906 270)
			(size 0.519938 1.4986)
			(layers "F.Cu" "F.Mask" "F.Paste")
			(net "M_H_CPU0_SA_DQ<1>")
		)
		(pad "10" smd rect
			(at -2.050034 -55.675022 270)
			(size 0.519938 1.4986)
			(layers "F.Cu" "F.Mask" "F.Paste")
			(net "GND")
		)
		(pad "11" smd rect
			(at -2.050034 -54.824884 270)
			(size 0.519938 1.4986)
			(layers "F.Cu" "F.Mask" "F.Paste")
			(net "M_H_CPU0_SA_DQS_DP<0>")
		)
		(pad "12" smd rect
			(at -2.050034 -53.975 270)
			(size 0.519938 1.4986)
			(layers "F.Cu" "F.Mask" "F.Paste")
			(net "M_H_CPU0_SA_DQS_DN<0>")
		)
		(pad "13" smd rect
			(at -2.050034 -53.125116 270)
			(size 0.519938 1.4986)
			(layers "F.Cu" "F.Mask" "F.Paste")
			(net "GND")
		)
		(pad "14" smd rect
			(at -2.050034 -52.274978 270)
			(size 0.519938 1.4986)
			(layers "F.Cu" "F.Mask" "F.Paste")
			(net "M_H_CPU0_SA_DQ<4>")
		)
		(pad "15" smd rect
			(at -2.050034 -51.425094 270)
			(size 0.519938 1.4986)
			(layers "F.Cu" "F.Mask" "F.Paste")
			(net "GND")
		)
		(pad "16" smd rect
			(at -2.050034 -50.574956 270)
			(size 0.519938 1.4986)
			(layers "F.Cu" "F.Mask" "F.Paste")
			(net "M_H_CPU0_SA_DQ<5>")
		)
		(pad "17" smd rect
			(at -2.050034 -49.725072 270)
			(size 0.519938 1.4986)
			(layers "F.Cu" "F.Mask" "F.Paste")
			(net "GND")
		)
		(pad "18" smd rect
			(at -2.050034 -48.874934 270)
			(size 0.519938 1.4986)
			(layers "F.Cu" "F.Mask" "F.Paste")
			(net "M_H_CPU0_SA_DQ<8>")
		)
		(pad "19" smd rect
			(at -2.050034 -48.02505 270)
			(size 0.519938 1.4986)
			(layers "F.Cu" "F.Mask" "F.Paste")
			(net "GND")
		)
		(pad "20" smd rect
			(at -2.050034 -47.174912 270)
			(size 0.519938 1.4986)
			(layers "F.Cu" "F.Mask" "F.Paste")
			(net "M_H_CPU0_SA_DQ<9>")
		)
		(pad "21" smd rect
			(at -2.050034 -46.325028 270)
			(size 0.519938 1.4986)
			(layers "F.Cu" "F.Mask" "F.Paste")
			(net "GND")
		)
		(pad "22" smd rect
			(at -2.050034 -45.47489 270)
			(size 0.519938 1.4986)
			(layers "F.Cu" "F.Mask" "F.Paste")
			(net "M_H_CPU0_SA_DQS_DP<1>")
		)
		(pad "23" smd rect
			(at -2.050034 -44.625006 270)
			(size 0.519938 1.4986)
			(layers "F.Cu" "F.Mask" "F.Paste")
			(net "M_H_CPU0_SA_DQS_DN<1>")
		)
		(pad "24" smd rect
			(at -2.050034 -43.775122 270)
			(size 0.519938 1.4986)
			(layers "F.Cu" "F.Mask" "F.Paste")
			(net "GND")
		)
		(pad "25" smd rect
			(at -2.050034 -42.924984 270)
			(size 0.519938 1.4986)
			(layers "F.Cu" "F.Mask" "F.Paste")
			(net "M_H_CPU0_SA_DQ<12>")
		)
		(pad "26" smd rect
			(at -2.050034 -42.0751 270)
			(size 0.519938 1.4986)
			(layers "F.Cu" "F.Mask" "F.Paste")
			(net "GND")
		)
		(pad "27" smd rect
			(at -2.050034 -41.224962 270)
			(size 0.519938 1.4986)
			(layers "F.Cu" "F.Mask" "F.Paste")
			(net "M_H_CPU0_SA_DQ<13>")
		)
		(pad "28" smd rect
			(at -2.050034 -40.375078 270)
			(size 0.519938 1.4986)
			(layers "F.Cu" "F.Mask" "F.Paste")
			(net "GND")
		)
		(pad "29" smd rect
			(at -2.050034 -39.52494 270)
			(size 0.519938 1.4986)
			(layers "F.Cu" "F.Mask" "F.Paste")
			(net "M_H_CPU0_SA_DQ<16>")
		)
		(pad "30" smd rect
			(at -2.050034 -38.675056 270)
			(size 0.519938 1.4986)
			(layers "F.Cu" "F.Mask" "F.Paste")
			(net "GND")
		)
		(pad "31" smd rect
			(at -2.050034 -37.824918 270)
			(size 0.519938 1.4986)
			(layers "F.Cu" "F.Mask" "F.Paste")
			(net "M_H_CPU0_SA_DQ<17>")
		)
		(pad "32" smd rect
			(at -2.050034 -36.975034 270)
			(size 0.519938 1.4986)
			(layers "F.Cu" "F.Mask" "F.Paste")
			(net "GND")
		)
		(pad "33" smd rect
			(at -2.050034 -36.124896 270)
			(size 0.519938 1.4986)
			(layers "F.Cu" "F.Mask" "F.Paste")
			(net "M_H_CPU0_SA_DQS_DP<2>")
		)
		(pad "34" smd rect
			(at -2.050034 -35.275012 270)
			(size 0.519938 1.4986)
			(layers "F.Cu" "F.Mask" "F.Paste")
			(net "M_H_CPU0_SA_DQS_DN<2>")
		)
		(pad "35" smd rect
			(at -2.050034 -34.425128 270)
			(size 0.519938 1.4986)
			(layers "F.Cu" "F.Mask" "F.Paste")
			(net "GND")
		)
		(pad "36" smd rect
			(at -2.050034 -33.57499 270)
			(size 0.519938 1.4986)
			(layers "F.Cu" "F.Mask" "F.Paste")
			(net "M_H_CPU0_SA_DQ<20>")
		)
		(pad "37" smd rect
			(at -2.050034 -32.725106 270)
			(size 0.519938 1.4986)
			(layers "F.Cu" "F.Mask" "F.Paste")
			(net "GND")
		)
		(pad "38" smd rect
			(at -2.050034 -31.874968 270)
			(size 0.519938 1.4986)
			(layers "F.Cu" "F.Mask" "F.Paste")
			(net "M_H_CPU0_SA_DQ<21>")
		)
		(pad "39" smd rect
			(at -2.050034 -31.025084 270)
			(size 0.519938 1.4986)
			(layers "F.Cu" "F.Mask" "F.Paste")
			(net "GND")
		)
		(pad "40" smd rect
			(at -2.050034 -30.174946 270)
			(size 0.519938 1.4986)
			(layers "F.Cu" "F.Mask" "F.Paste")
			(net "M_H_CPU0_SA_DQ<24>")
		)
		(pad "41" smd rect
			(at -2.050034 -29.325062 270)
			(size 0.519938 1.4986)
			(layers "F.Cu" "F.Mask" "F.Paste")
			(net "GND")
		)
		(pad "42" smd rect
			(at -2.050034 -28.474924 270)
			(size 0.519938 1.4986)
			(layers "F.Cu" "F.Mask" "F.Paste")
			(net "M_H_CPU0_SA_DQ<25>")
		)
		(pad "43" smd rect
			(at -2.050034 -27.62504 270)
			(size 0.519938 1.4986)
			(layers "F.Cu" "F.Mask" "F.Paste")
			(net "GND")
		)
		(pad "44" smd rect
			(at -2.050034 -26.774902 270)
			(size 0.519938 1.4986)
			(layers "F.Cu" "F.Mask" "F.Paste")
			(net "M_H_CPU0_SA_DQS_DP<3>")
		)
		(pad "45" smd rect
			(at -2.050034 -25.925018 270)
			(size 0.519938 1.4986)
			(layers "F.Cu" "F.Mask" "F.Paste")
			(net "M_H_CPU0_SA_DQS_DN<3>")
		)
		(pad "46" smd rect
			(at -2.050034 -25.07488 270)
			(size 0.519938 1.4986)
			(layers "F.Cu" "F.Mask" "F.Paste")
			(net "GND")
		)
		(pad "47" smd rect
			(at -2.050034 -24.224996 270)
			(size 0.519938 1.4986)
			(layers "F.Cu" "F.Mask" "F.Paste")
			(net "M_H_CPU0_SA_DQ<28>")
		)
		(pad "48" smd rect
			(at -2.050034 -23.375112 270)
			(size 0.519938 1.4986)
			(layers "F.Cu" "F.Mask" "F.Paste")
			(net "GND")
		)
		(pad "49" smd rect
			(at -2.050034 -22.524974 270)
			(size 0.519938 1.4986)
			(layers "F.Cu" "F.Mask" "F.Paste")
			(net "M_H_CPU0_SA_DQ<29>")
		)
		(pad "50" smd rect
			(at -2.050034 -21.67509 270)
			(size 0.519938 1.4986)
			(layers "F.Cu" "F.Mask" "F.Paste")
			(net "GND")
		)
		(pad "51" smd rect
			(at -2.050034 -20.824952 270)
			(size 0.519938 1.4986)
			(layers "F.Cu" "F.Mask" "F.Paste")
			(net "M_H_CPU0_SA_CB<0>")
		)
		(pad "52" smd rect
			(at -2.050034 -19.975068 270)
			(size 0.519938 1.4986)
			(layers "F.Cu" "F.Mask" "F.Paste")
			(net "GND")
		)
		(pad "53" smd rect
			(at -2.050034 -19.12493 270)
			(size 0.519938 1.4986)
			(layers "F.Cu" "F.Mask" "F.Paste")
			(net "M_H_CPU0_SA_CB<1>")
		)
		(pad "54" smd rect
			(at -2.050034 -18.275046 270)
			(size 0.519938 1.4986)
			(layers "F.Cu" "F.Mask" "F.Paste")
			(net "GND")
		)
		(pad "55" smd rect
			(at -2.050034 -17.424908 270)
			(size 0.519938 1.4986)
			(layers "F.Cu" "F.Mask" "F.Paste")
			(net "M_H_CPU0_SA_DQS_DP<4>")
		)
		(pad "56" smd rect
			(at -2.050034 -16.575024 270)
			(size 0.519938 1.4986)
			(layers "F.Cu" "F.Mask" "F.Paste")
			(net "M_H_CPU0_SA_DQS_DN<4>")
		)
		(pad "57" smd rect
			(at -2.050034 -15.724886 270)
			(size 0.519938 1.4986)
			(layers "F.Cu" "F.Mask" "F.Paste")
			(net "GND")
		)
		(pad "58" smd rect
			(at -2.050034 -14.875002 270)
			(size 0.519938 1.4986)
			(layers "F.Cu" "F.Mask" "F.Paste")
			(net "M_H_CPU0_SA_CB<4>")
		)
		(pad "59" smd rect
			(at -2.050034 -14.025118 270)
			(size 0.519938 1.4986)
			(layers "F.Cu" "F.Mask" "F.Paste")
			(net "GND")
		)
		(pad "60" smd rect
			(at -2.050034 -13.17498 270)
			(size 0.519938 1.4986)
			(layers "F.Cu" "F.Mask" "F.Paste")
			(net "M_H_CPU0_SA_CB<5>")
		)
		(pad "61" smd rect
			(at -2.050034 -12.325096 270)
			(size 0.519938 1.4986)
			(layers "F.Cu" "F.Mask" "F.Paste")
			(net "GND")
		)
		(pad "62" smd rect
			(at -2.050034 -11.474958 270)
			(size 0.519938 1.4986)
			(layers "F.Cu" "F.Mask" "F.Paste")
			(net "M_H_CPU0_ALERT_N")
		)
		(pad "63" smd rect
			(at -2.050034 -10.625074 270)
			(size 0.519938 1.4986)
			(layers "F.Cu" "F.Mask" "F.Paste")
			(net "GND")
		)
		(pad "64" smd rect
			(at -2.050034 -9.774936 270)
			(size 0.519938 1.4986)
			(layers "F.Cu" "F.Mask" "F.Paste")
			(net "M_H_CPU0_SA_CS_N<0>")
		)
		(pad "65" smd rect
			(at -2.050034 -8.925052 270)
			(size 0.519938 1.4986)
			(layers "F.Cu" "F.Mask" "F.Paste")
			(net "GND")
		)
		(pad "66" smd rect
			(at -2.050034 -8.074914 270)
			(size 0.519938 1.4986)
			(layers "F.Cu" "F.Mask" "F.Paste")
			(net "M_H_CPU0_SA_CA<0>")
		)
		(pad "67" smd rect
			(at -2.050034 -7.22503 270)
			(size 0.519938 1.4986)
			(layers "F.Cu" "F.Mask" "F.Paste")
			(net "GND")
		)
		(pad "68" smd rect
			(at -2.050034 -6.374892 270)
			(size 0.519938 1.4986)
			(layers "F.Cu" "F.Mask" "F.Paste")
			(net "M_H_CPU0_SA_CA<2>")
		)
		(pad "69" smd rect
			(at -2.050034 -5.525008 270)
			(size 0.519938 1.4986)
			(layers "F.Cu" "F.Mask" "F.Paste")
			(net "GND")
		)
		(pad "70" smd rect
			(at -2.050034 -4.675124 270)
			(size 0.519938 1.4986)
			(layers "F.Cu" "F.Mask" "F.Paste")
			(net "M_H_CPU0_SA_CA<4>")
		)
		(pad "71" smd rect
			(at -2.050034 -3.824986 270)
			(size 0.519938 1.4986)
			(layers "F.Cu" "F.Mask" "F.Paste")
			(net "GND")
		)
		(pad "72" smd rect
			(at -2.050034 -2.975102 270)
			(size 0.519938 1.4986)
			(layers "F.Cu" "F.Mask" "F.Paste")
			(net "M_H_CPU0_SA_CA<6>")
		)
		(pad "73" smd rect
			(at -2.050034 -2.124964 270)
			(size 0.519938 1.4986)
			(layers "F.Cu" "F.Mask" "F.Paste")
			(net "GND")
		)
		(pad "74" smd rect
			(at -2.050034 -1.27508 270)
			(size 0.519938 1.4986)
			(layers "F.Cu" "F.Mask" "F.Paste")
			(net "M_H_CPU0_SA_PAR")
		)
		(pad "75" smd rect
			(at -2.050034 -0.424942 270)
			(size 0.519938 1.4986)
			(layers "F.Cu" "F.Mask" "F.Paste")
			(net "GND")
		)
		(pad "76" smd rect
			(at -2.050034 5.525008 270)
			(size 0.519938 1.4986)
			(layers "F.Cu" "F.Mask" "F.Paste")
			(net "M_H_CPU0_SB_CA<0>")
		)
		(pad "77" smd rect
			(at -2.050034 6.374892 270)
			(size 0.519938 1.4986)
			(layers "F.Cu" "F.Mask" "F.Paste")
			(net "GND")
		)
		(pad "78" smd rect
			(at -2.050034 7.22503 270)
			(size 0.519938 1.4986)
			(layers "F.Cu" "F.Mask" "F.Paste")
			(net "M_H_CPU0_SB_CA<2>")
		)
		(pad "79" smd rect
			(at -2.050034 8.074914 270)
			(size 0.519938 1.4986)
			(layers "F.Cu" "F.Mask" "F.Paste")
			(net "GND")
		)
		(pad "80" smd rect
			(at -2.050034 8.925052 270)
			(size 0.519938 1.4986)
			(layers "F.Cu" "F.Mask" "F.Paste")
			(net "M_H_CPU0_SB_CA<4>")
		)
		(pad "81" smd rect
			(at -2.050034 9.774936 270)
			(size 0.519938 1.4986)
			(layers "F.Cu" "F.Mask" "F.Paste")
			(net "GND")
		)
		(pad "82" smd rect
			(at -2.050034 10.625074 270)
			(size 0.519938 1.4986)
			(layers "F.Cu" "F.Mask" "F.Paste")
			(net "M_H_CPU0_SB_CA<6>")
		)
		(pad "83" smd rect
			(at -2.050034 11.474958 270)
			(size 0.519938 1.4986)
			(layers "F.Cu" "F.Mask" "F.Paste")
			(net "GND")
		)
		(pad "84" smd rect
			(at -2.050034 12.325096 270)
			(size 0.519938 1.4986)
			(layers "F.Cu" "F.Mask" "F.Paste")
			(net "M_H_CPU0_SB_CS_N<0>")
		)
		(pad "85" smd rect
			(at -2.050034 13.17498 270)
			(size 0.519938 1.4986)
			(layers "F.Cu" "F.Mask" "F.Paste")
			(net "GND")
		)
		(pad "86" smd rect
			(at -2.050034 14.025118 270)
			(size 0.519938 1.4986)
			(layers "F.Cu" "F.Mask" "F.Paste")
			(net "M_H_CPU0_SA_RSP<0>")
		)
		(pad "87" smd rect
			(at -2.050034 14.875002 270)
			(size 0.519938 1.4986)
			(layers "F.Cu" "F.Mask" "F.Paste")
			(net "M_H_CPU0_SB_RSP<0>")
		)
		(pad "88" smd rect
			(at -2.050034 15.724886 270)
			(size 0.519938 1.4986)
			(layers "F.Cu" "F.Mask" "F.Paste")
			(net "GND")
		)
		(pad "89" smd rect
			(at -2.050034 16.575024 270)
			(size 0.519938 1.4986)
			(layers "F.Cu" "F.Mask" "F.Paste")
			(net "M_H_CPU0_SB_CB<4>")
		)
		(pad "90" smd rect
			(at -2.050034 17.424908 270)
			(size 0.519938 1.4986)
			(layers "F.Cu" "F.Mask" "F.Paste")
			(net "GND")
		)
		(pad "91" smd rect
			(at -2.050034 18.275046 270)
			(size 0.519938 1.4986)
			(layers "F.Cu" "F.Mask" "F.Paste")
			(net "M_H_CPU0_SB_CB<5>")
		)
		(pad "92" smd rect
			(at -2.050034 19.12493 270)
			(size 0.519938 1.4986)
			(layers "F.Cu" "F.Mask" "F.Paste")
			(net "GND")
		)
		(pad "93" smd rect
			(at -2.050034 19.975068 270)
			(size 0.519938 1.4986)
			(layers "F.Cu" "F.Mask" "F.Paste")
			(net "M_H_CPU0_SB_DQS_DP<9>")
		)
		(pad "94" smd rect
			(at -2.050034 20.824952 270)
			(size 0.519938 1.4986)
			(layers "F.Cu" "F.Mask" "F.Paste")
			(net "M_H_CPU0_SB_DQS_DN<9>")
		)
		(pad "95" smd rect
			(at -2.050034 21.67509 270)
			(size 0.519938 1.4986)
			(layers "F.Cu" "F.Mask" "F.Paste")
			(net "GND")
		)
		(pad "96" smd rect
			(at -2.050034 22.524974 270)
			(size 0.519938 1.4986)
			(layers "F.Cu" "F.Mask" "F.Paste")
			(net "M_H_CPU0_SB_CB<0>")
		)
		(pad "97" smd rect
			(at -2.050034 23.375112 270)
			(size 0.519938 1.4986)
			(layers "F.Cu" "F.Mask" "F.Paste")
			(net "GND")
		)
		(pad "98" smd rect
			(at -2.050034 24.224996 270)
			(size 0.519938 1.4986)
			(layers "F.Cu" "F.Mask" "F.Paste")
			(net "M_H_CPU0_SB_CB<1>")
		)
		(pad "99" smd rect
			(at -2.050034 25.07488 270)
			(size 0.519938 1.4986)
			(layers "F.Cu" "F.Mask" "F.Paste")
			(net "GND")
		)
		(pad "100" smd rect
			(at -2.050034 25.925018 270)
			(size 0.519938 1.4986)
			(layers "F.Cu" "F.Mask" "F.Paste")
			(net "M_H_CPU0_SB_DQ<0>")
		)
		(pad "101" smd rect
			(at -2.050034 26.774902 270)
			(size 0.519938 1.4986)
			(layers "F.Cu" "F.Mask" "F.Paste")
			(net "GND")
		)
		(pad "102" smd rect
			(at -2.050034 27.62504 270)
			(size 0.519938 1.4986)
			(layers "F.Cu" "F.Mask" "F.Paste")
			(net "M_H_CPU0_SB_DQ<1>")
		)
		(pad "103" smd rect
			(at -2.050034 28.474924 270)
			(size 0.519938 1.4986)
			(layers "F.Cu" "F.Mask" "F.Paste")
			(net "GND")
		)
		(pad "104" smd rect
			(at -2.050034 29.325062 270)
			(size 0.519938 1.4986)
			(layers "F.Cu" "F.Mask" "F.Paste")
			(net "M_H_CPU0_SB_DQS_DP<0>")
		)
		(pad "105" smd rect
			(at -2.050034 30.174946 270)
			(size 0.519938 1.4986)
			(layers "F.Cu" "F.Mask" "F.Paste")
			(net "M_H_CPU0_SB_DQS_DN<0>")
		)
		(pad "106" smd rect
			(at -2.050034 31.025084 270)
			(size 0.519938 1.4986)
			(layers "F.Cu" "F.Mask" "F.Paste")
			(net "GND")
		)
		(pad "107" smd rect
			(at -2.050034 31.874968 270)
			(size 0.519938 1.4986)
			(layers "F.Cu" "F.Mask" "F.Paste")
			(net "M_H_CPU0_SB_DQ<4>")
		)
		(pad "108" smd rect
			(at -2.050034 32.725106 270)
			(size 0.519938 1.4986)
			(layers "F.Cu" "F.Mask" "F.Paste")
			(net "GND")
		)
		(pad "109" smd rect
			(at -2.050034 33.57499 270)
			(size 0.519938 1.4986)
			(layers "F.Cu" "F.Mask" "F.Paste")
			(net "M_H_CPU0_SB_DQ<5>")
		)
		(pad "110" smd rect
			(at -2.050034 34.425128 270)
			(size 0.519938 1.4986)
			(layers "F.Cu" "F.Mask" "F.Paste")
			(net "GND")
		)
		(pad "111" smd rect
			(at -2.050034 35.275012 270)
			(size 0.519938 1.4986)
			(layers "F.Cu" "F.Mask" "F.Paste")
			(net "M_H_CPU0_SB_DQ<8>")
		)
		(pad "112" smd rect
			(at -2.050034 36.124896 270)
			(size 0.519938 1.4986)
			(layers "F.Cu" "F.Mask" "F.Paste")
			(net "GND")
		)
	)
)
